# S9S_MB_2U (Grand Teton) — schematic netlist excerpt (pin names and nets, part order shuffled) for the footprints in the layout excerpt that follows; sources: Cadence DE-HDL packaged netlist, KiCad conversion of 03242023_DA0F0TMBIJ0_F0T_Motherboard_J_brd_V01_OCP.brd

PR3928  Q_RES  0 5% CHIP  pkg 0402LF  page 301 : A = HSC_ON ; B = HSC_ON_R
R775  Q_RES  10 1% CHIP  pkg 0402LF  page 131 : A = JTAG_DBP_TMS_R ; B = JTAG_DBP_TMS

(kicad_pcb
	(version 20260206)
	(generator "pcbnew")
	(generator_version "10.0")
	(general
		(thickness 1.6)
		(legacy_teardrops no)
	)
	(paper "A4")
	(title_block
		(title "03242023_DA0F0TMBIJ0_F0T_Motherboard_J_brd_V01_OCP.brd")
		(comment 1 "Grand Teton / footprints 177-178 of 6105")
	)
	(layers
		(0 "F.Cu" signal "TOP")
		(4 "In1.Cu" signal "GND")
		(6 "In2.Cu" signal "IN1")
		(8 "In3.Cu" signal "GND1")
		(10 "In4.Cu" signal "IN2")
		(12 "In5.Cu" signal "GND2")
		(14 "In6.Cu" signal "IN3")
		(16 "In7.Cu" signal "GND3")
		(18 "In8.Cu" signal "VCC")
		(20 "In9.Cu" signal "VCC1")
		(22 "In10.Cu" signal "GND4")
		(24 "In11.Cu" signal "IN4")
		(26 "In12.Cu" signal "GND5")
		(28 "In13.Cu" signal "IN5")
		(30 "In14.Cu" signal "GND6")
		(32 "In15.Cu" signal "IN6")
		(34 "In16.Cu" signal "GND7")
		(2 "B.Cu" signal "BOTTOM")
		(9 "F.Adhes" user "F.Adhesive")
		(11 "B.Adhes" user "B.Adhesive")
		(13 "F.Paste" user "Package Geometry/Pastemask Top")
		(15 "B.Paste" user "Package Geometry/Pastemask Bottom")
		(5 "F.SilkS" user "Ref Des/Silkscreen Top")
		(7 "B.SilkS" user "Ref Des/Silkscreen Bottom")
		(1 "F.Mask" user "Board Geometry/Soldermask Top")
		(3 "B.Mask" user "Board Geometry/Soldermask Bottom")
		(17 "Dwgs.User" user "User.Drawings")
		(19 "Cmts.User" user "User.Comments")
		(21 "Eco1.User" user "User.Eco1")
		(23 "Eco2.User" user "User.Eco2")
		(25 "Edge.Cuts" user "Board Geometry/Outline")
		(27 "Margin" user)
		(31 "F.CrtYd" user "Package Geometry/Place Bound Top")
		(29 "B.CrtYd" user "Package Geometry/Place Bound Bottom")
		(35 "F.Fab" user "Ref Des/Assembly Top")
		(33 "B.Fab" user "Ref Des/Assembly Bottom")
	)
	(footprint ""
		(layer "F.Cu")
		(at 192.052448 -402.128482 180)
		(property "Reference" "PR3928"
			(at 0 0 180)
			(layer "F.SilkS")
			(hide yes)
			(effects
				(font
					(size 1.27 1.27)
				)
			)
		)
		(property "Value" ""
			(at 0 0 180)
			(layer "F.Fab")
			(effects
				(font
					(size 1.27 1.27)
				)
			)
		)
		(duplicate_pad_numbers_are_jumpers no)
		(fp_line
			(start 0.7874 0.4064)
			(end -0.7874 0.4064)
			(stroke
				(width 0.1524)
				(type default)
			)
			(layer "F.SilkS")
		)
		(fp_line
			(start 0.7874 -0.4064)
			(end 0.7874 0.4064)
			(stroke
				(width 0.1524)
				(type default)
			)
			(layer "F.SilkS")
		)
		(fp_line
			(start -0.7874 0.4064)
			(end -0.7874 -0.4064)
			(stroke
				(width 0.1524)
				(type default)
			)
			(layer "F.SilkS")
		)
		(fp_line
			(start -0.7874 -0.4064)
			(end 0.7874 -0.4064)
			(stroke
				(width 0.1524)
				(type default)
			)
			(layer "F.SilkS")
		)
		(fp_line
			(start 0.67945 0.3048)
			(end 0.120396 0.3048)
			(stroke
				(width 0.1)
				(type default)
			)
			(layer "F.Fab")
		)
		(fp_line
			(start 0.67945 -0.3048)
			(end 0.67945 0.3048)
			(stroke
				(width 0.1)
				(type default)
			)
			(layer "F.Fab")
		)
		(fp_line
			(start 0.12065 -0.2794)
			(end 0.12065 -0.3048)
			(stroke
				(width 0.1)
				(type default)
			)
			(layer "F.Fab")
		)
		(fp_line
			(start 0.12065 -0.3048)
			(end 0.67945 -0.3048)
			(stroke
				(width 0.1)
				(type default)
			)
			(layer "F.Fab")
		)
		(fp_line
			(start 0.120396 0.3048)
			(end 0.120396 0.2794)
			(stroke
				(width 0.1)
				(type default)
			)
			(layer "F.Fab")
		)
		(fp_line
			(start 0.120396 0.2794)
			(end -0.12065 0.2794)
			(stroke
				(width 0.1)
				(type default)
			)
			(layer "F.Fab")
		)
		(fp_line
			(start -0.12065 0.3048)
			(end -0.67945 0.3048)
			(stroke
				(width 0.1)
				(type default)
			)
			(layer "F.Fab")
		)
		(fp_line
			(start -0.12065 0.2794)
			(end -0.12065 0.3048)
			(stroke
				(width 0.1)
				(type default)
			)
			(layer "F.Fab")
		)
		(fp_line
			(start -0.12065 -0.2794)
			(end 0.12065 -0.2794)
			(stroke
				(width 0.1)
				(type default)
			)
			(layer "F.Fab")
		)
		(fp_line
			(start -0.12065 -0.305054)
			(end -0.12065 -0.2794)
			(stroke
				(width 0.1)
				(type default)
			)
			(layer "F.Fab")
		)
		(fp_line
			(start -0.67945 0.3048)
			(end -0.67945 -0.305054)
			(stroke
				(width 0.1)
				(type default)
			)
			(layer "F.Fab")
		)
		(fp_line
			(start -0.67945 -0.305054)
			(end -0.12065 -0.305054)
			(stroke
				(width 0.1)
				(type default)
			)
			(layer "F.Fab")
		)
		(pad "1" smd circle
			(at -0.40005 0 180)
			(size 0 0)
			(layers "F.Cu" "F.Mask" "F.Paste")
			(net "HSC_ON")
		)
		(pad "2" smd circle
			(at 0.40005 0 180)
			(size 0 0)
			(layers "F.Cu" "F.Mask" "F.Paste")
			(net "HSC_ON_R")
		)
	)
	(footprint ""
		(layer "F.Cu")
		(at 385.699 -69.179948 180)
		(property "Reference" "R775"
			(at 0 0 180)
			(layer "F.SilkS")
			(hide yes)
			(effects
				(font
					(size 1.27 1.27)
				)
			)
		)
		(property "Value" ""
			(at 0 0 180)
			(layer "F.Fab")
			(effects
				(font
					(size 1.27 1.27)
				)
			)
		)
		(duplicate_pad_numbers_are_jumpers no)
		(fp_line
			(start 0.7874 0.4064)
			(end -0.7874 0.4064)
			(stroke
				(width 0.1524)
				(type default)
			)
			(layer "F.SilkS")
		)
		(fp_line
			(start 0.7874 -0.4064)
			(end 0.7874 0.4064)
			(stroke
				(width 0.1524)
				(type default)
			)
			(layer "F.SilkS")
		)
		(fp_line
			(start -0.7874 0.4064)
			(end -0.7874 -0.4064)
			(stroke
				(width 0.1524)
				(type default)
			)
			(layer "F.SilkS")
		)
		(fp_line
			(start -0.7874 -0.4064)
			(end 0.7874 -0.4064)
			(stroke
				(width 0.1524)
				(type default)
			)
			(layer "F.SilkS")
		)
		(fp_line
			(start 0.67945 0.3048)
			(end 0.120396 0.3048)
			(stroke
				(width 0.1)
				(type default)
			)
			(layer "F.Fab")
		)
		(fp_line
			(start 0.67945 -0.3048)
			(end 0.67945 0.3048)
			(stroke
				(width 0.1)
				(type default)
			)
			(layer "F.Fab")
		)
		(fp_line
			(start 0.12065 -0.2794)
			(end 0.12065 -0.3048)
			(stroke
				(width 0.1)
				(type default)
			)
			(layer "F.Fab")
		)
		(fp_line
			(start 0.12065 -0.3048)
			(end 0.67945 -0.3048)
			(stroke
				(width 0.1)
				(type default)
			)
			(layer "F.Fab")
		)
		(fp_line
			(start 0.120396 0.3048)
			(end 0.120396 0.2794)
			(stroke
				(width 0.1)
				(type default)
			)
			(layer "F.Fab")
		)
		(fp_line
			(start 0.120396 0.2794)
			(end -0.12065 0.2794)
			(stroke
				(width 0.1)
				(type default)
			)
			(layer "F.Fab")
		)
		(fp_line
			(start -0.12065 0.3048)
			(end -0.67945 0.3048)
			(stroke
				(width 0.1)
				(type default)
			)
			(layer "F.Fab")
		)
		(fp_line
			(start -0.12065 0.2794)
			(end -0.12065 0.3048)
			(stroke
				(width 0.1)
				(type default)
			)
			(layer "F.Fab")
		)
		(fp_line
			(start -0.12065 -0.2794)
			(end 0.12065 -0.2794)
			(stroke
				(width 0.1)
				(type default)
			)
			(layer "F.Fab")
		)
		(fp_line
			(start -0.12065 -0.305054)
			(end -0.12065 -0.2794)
			(stroke
				(width 0.1)
				(type default)
			)
			(layer "F.Fab")
		)
		(fp_line
			(start -0.67945 0.3048)
			(end -0.67945 -0.305054)
			(stroke
				(width 0.1)
				(type default)
			)
			(layer "F.Fab")
		)
		(fp_line
			(start -0.67945 -0.305054)
			(end -0.12065 -0.305054)
			(stroke
				(width 0.1)
				(type default)
			)
			(layer "F.Fab")
		)
		(pad "1" smd circle
			(at -0.40005 0 180)
			(size 0 0)
			(layers "F.Cu" "F.Mask" "F.Paste")
			(net "JTAG_DBP_TMS_R")
		)
		(pad "2" smd circle
			(at 0.40005 0 180)
			(size 0 0)
			(layers "F.Cu" "F.Mask" "F.Paste")
			(net "JTAG_DBP_TMS")
		)
	)
)
